#ISCELL
  pure_quanta quanta_title_block_c *
  *
#ISCELL
  logical_power gnd *
  page244_i1
#CELL
  pure_quanta q_res *
  page244_i10
#CELL
  pure_quanta q_cap *
  page244_i11
#CELL
  pure_quanta q_cap *
  page244_i12
#ISCELL
  standard offpage *
  page244_i13
#CELL
  pure_quanta q_cap *
  page244_i14
#ISCELL
  logical_power gnd *
  page244_i15
#CELL
  pure_quanta q_res *
  page244_i16
#ISCELL
  logical_power gnd *
  page244_i17
#ISCELL
  logical_power gnd *
  page244_i18
#ISCELL
  logical_power gnd *
  page244_i19
#CELL
  pure_quanta q_cap *
  page244_i2
#CELL
  pure_quanta rs53318lr *
  page244_i20
#CELL
  pure_quanta q_cap *
  page244_i21
#CELL
  pure_quanta q_cap *
  page244_i22
#ISCELL
  logical_power gnd *
  page244_i23
#ISCELL
  logical_power gnd *
  page244_i24
#CELL
  pure_quanta q_res *
  page244_i25
#CELL
  pure_quanta q_cap *
  page244_i26
#CELL
  pure_quanta q_res *
  page244_i27
#CELL
  pure_quanta q_res *
  page244_i28
#ISCELL
  logical_power p1v0_aux *
  page244_i3
#CELL
  pure_quanta q_inductor *
  page244_i30
#ISCELL
  standard offpage *
  page244_i31
#CELL
  pure_quanta q_capp *
  page244_i32
#CELL
  pure_quanta q_cap *
  page244_i33
#CELL
  pure_quanta q_cap *
  page244_i34
#ISCELL
  logical_power gnd *
  page244_i35
#CELL
  pure_quanta q_cap *
  page244_i36
#ISCELL
  logical_power universal_power *
  page244_i37
#ISCELL
  logical_power p1v0 *
  page244_i38
#CELL
  pure_quanta q_res *
  page244_i39
#ISCELL
  logical_power gnd *
  page244_i4
#CELL
  pure_quanta q_inductor *
  page244_i5
#ISCELL
  logical_power gnd *
  page244_i6
#CELL
  pure_quanta q_cap *
  page244_i7
#CELL
  pure_quanta q_cap *
  page244_i8
#ISCELL
  logical_power universal_power *
  page244_i9
